;LEADER: 12 
;HEADER: 
;CODE  : ASCII 
;FILE  : 9051_F0T_Panel_BD_Front_D_v02_20221209_1310-1-4.drl for  ... layers TOP and BOTTOM
;DESIGN: 9051_F0T_Panel_BD_Front_D_v02_20221209_1310.brd
;   Holesize 1. = 9.840000 Tolerance = +2.000000/-2.000000 PLATED MILS Quantity = 8
;   Holesize 2. = 10.000000 Tolerance = +0.000000/-10.000000 PLATED MILS Quantity = 262
;   Holesize 3. = 22.000000 Tolerance = +3.000000/-3.000000 PLATED MILS Quantity = 16
;   Holesize 4. = 26.000000 Tolerance = +1.960000/-1.960000 PLATED MILS Quantity = 4
;   Holesize 5. = 28.000000 Tolerance = +3.000000/-3.000000 PLATED MILS Quantity = 9
;   Holesize 6. = 32.000000 Tolerance = +6.000000/-0.000000 PLATED MILS Quantity = 4
;   Holesize 7. = 38.000000 Tolerance = +2.000000/-2.000000 PLATED MILS Quantity = 3
;   Holesize 8. = 67.000000 Tolerance = +3.000000/-3.000000 PLATED MILS Quantity = 6
;   Holesize 9. = 41.000000 Tolerance = +2.000000/-2.000000 NON_PLATED MILS Quantity = 16
;   Holesize 10. = 52.000000 Tolerance = +1.960000/-1.960000 NON_PLATED MILS Quantity = 2
;   Holesize 11. = 119.000000 Tolerance = +2.000000/-2.000000 NON_PLATED MILS Quantity = 2
;   Holesize 12. = 125.000000 Tolerance = +2.000000/-0.000000 NON_PLATED MILS Quantity = 3
;   Holesize 13. = 158.000000 Tolerance = +2.000000/-2.000000 NON_PLATED MILS Quantity = 2
%
G90
X0370195Y0247618
X0370195Y0257618
X0370195Y0083000
X0370195Y0093000
X0380195Y0093000
X0380195Y0083000
X0380195Y0257618
X0380195Y0247618
M00
X0060867Y0003014
X0046184Y0003014
X0005192Y0003841
X0027028Y0003019
X0065000Y0073500
X0042400Y0086500
X0075425Y0102000
X0073000Y0087000
X0008000Y0103500
X0073000Y0091000
X0073000Y0095000
X0059500Y0095000
X0052000Y0081000
X0041500Y0103500
X0010315Y0013000
X0072555Y0046921
X0063600Y0034192
X0062500Y0055000
X0016000Y0098441
X0008000Y0099500
X0077453Y0077500
X0059586Y0040000
X0077382Y0058000
X0048941Y0089500
X0054059Y0102500
X0003004Y0090860
X0068720Y0054000
X0070075Y0064500
X0059500Y0055000
X0066925Y0070000
X0064500Y0063500
X0078340Y0136000
X0078500Y0112500
X0078500Y0110000
X0008000Y0114500
X0067000Y0177500
X0066500Y0193500
X0066500Y0189500
X0011500Y0188000
X0011500Y0196000
X0066500Y0185500
X0076000Y0126500
X0076000Y0123000
X0066500Y0181500
X0059500Y0117960
X0041038Y0112537
X0070500Y0177500
X0066000Y0118000
X0070000Y0138500
X0016000Y0109441
X0008000Y0110500
X0064075Y0200000
X0003004Y0106468
X0003004Y0126468
X0003004Y0146468
X0003004Y0166468
X0003004Y0186468
X0033000Y0186000
X0011500Y0184000
X0011500Y0192000
X0011500Y0200000
X0076500Y0231500
X0070000Y0258000
X0072500Y0258000
X0019500Y0241500
X0019500Y0233500
X0019500Y0225500
X0065925Y0247000
X0019500Y0217500
X0019500Y0209500
X0055925Y0204000
X0011500Y0204000
X0076500Y0235500
X0076500Y0239500
X0068500Y0231500
X0066500Y0258000
X0064000Y0258000
X0068308Y0288205
X0075394Y0288205
X0013984Y0279449
X0017499Y0270964
X0025984Y0267449
X0034469Y0270964
X0037984Y0279449
X0078937Y0270653
X0075700Y0263900
X0076500Y0227500
X0019500Y0245500
X0019500Y0237500
X0069075Y0247000
X0071851Y0288205
X0057800Y0263900
X0056500Y0261000
X0076400Y0258000
X0064764Y0288205
X0059075Y0204000
X0007337Y0292952
X0007348Y0302588
X0003004Y0206468
X0003004Y0226468
X0003004Y0246468
X0041000Y0213532
X0019500Y0229500
X0019500Y0213500
X0019500Y0221500
X0068968Y0336145
X0016801Y0311946
X0035701Y0311937
X0051404Y0316245
X0053595Y0331234
X0083076Y0336146
X0103076Y0336146
X0116870Y0334863
X0118455Y0323862
X0129715Y0311960
X0144561Y0311483
X0089567Y0288205
X0096654Y0288205
X0080119Y0288205
X0084843Y0288205
X0101378Y0288205
X0093111Y0270653
X0086024Y0270653
X0106103Y0288205
X0107284Y0270653
X0100197Y0270653
X0093111Y0288205
X0151705Y0252655
X0151704Y0232645
X0151662Y0212615
X0092500Y0126000
X0080310Y0138735
X0088500Y0123500
X0134500Y0119000
X0134500Y0122500
X0134500Y0126000
X0134500Y0129500
X0134500Y0133000
X0134500Y0136500
X0148500Y0108000
X0083500Y0129500
X0083500Y0133000
X0115000Y0150500
X0115000Y0147000
X0112000Y0150500
X0112000Y0147000
X0094500Y0129000
X0081500Y0126500
X0148500Y0104000
X0148500Y0112000
X0148500Y0115500
X0148500Y0119000
X0148500Y0122500
X0148500Y0126000
X0148500Y0129500
X0148500Y0133000
X0148500Y0136500
X0120500Y0126000
X0120500Y0133000
X0120500Y0129500
X0120500Y0136500
X0118000Y0116500
X0133500Y0160000
X0132500Y0185000
X0151663Y0192669
X0151705Y0172913
X0151683Y0151482
X0151684Y0132682
X0151684Y0112798
X0081000Y0091000
X0109812Y0016716
X0111965Y0011716
X0081000Y0095000
X0106954Y0021716
X0127500Y0006716
X0137000Y0092000
X0106970Y0068327
X0106970Y0065827
X0139500Y0010500
X0137000Y0088000
X0132000Y0010500
X0137000Y0084500
X0148500Y0100000
X0148500Y0092000
X0148500Y0084000
X0148500Y0076000
X0122130Y0030217
X0107318Y0063176
X0084500Y0095000
X0099000Y0065500
X0091000Y0018500
X0099500Y0009000
X0148221Y0043425
X0144706Y0034940
X0136221Y0031425
X0127736Y0034940
X0124221Y0043425
X0081000Y0008000
X0128385Y0080000
X0148500Y0096000
X0148500Y0080000
X0148500Y0088000
X0151683Y0090942
X0151706Y0072716
X0151688Y0013776
X0150330Y0004601
X0113181Y0031701
X0118500Y0006716
X0081729Y0077772
X0084500Y0076500
X0136936Y0003035
X0117186Y0003014
X0098502Y0003016
X0080697Y0003016
X0378830Y0614095
X0370816Y0614080
X0368301Y0614065
X0373566Y0614080
X0376081Y0614095
X0368287Y0610797
X0370802Y0610812
X0378816Y0610797
X0369510Y0607802
X0340010Y0607802
X0349316Y0610797
X0351831Y0610812
X0346581Y0614095
X0344066Y0614080
X0341302Y0610812
X0338787Y0610797
X0341316Y0614080
X0338801Y0614065
X0349330Y0614095
X0351845Y0614080
X0350539Y0607802
X0340461Y0434698
X0339155Y0428420
X0341670Y0428405
X0349684Y0428420
X0352199Y0428435
X0346934Y0428420
X0344419Y0428405
X0352213Y0431703
X0349698Y0431688
X0339169Y0431688
X0341684Y0431703
X0350990Y0434698
X0369961Y0330884
X0368655Y0324606
X0371170Y0324591
X0379184Y0324606
X0376434Y0324606
X0373919Y0324591
X0379198Y0327874
X0368669Y0327874
X0371184Y0327889
X0381699Y0324621
X0381713Y0327889
X0380490Y0330884
X0380039Y0607802
X0381345Y0614080
X0381331Y0610812
M00
X0009218Y0058661
X0013553Y0048198
X0024016Y0043863
X0034479Y0048198
X0038814Y0058661
X0034479Y0069124
X0024016Y0073459
X0013553Y0069124
X0114336Y0247543
X0118671Y0237080
X0129134Y0232745
X0139597Y0237080
X0143932Y0247543
X0139597Y0258006
X0129134Y0262341
X0118671Y0258006
M00
X0061516Y0314961
X0061516Y0326772
X0110532Y0314961
X0110532Y0326772
M00
X0101969Y0076102
X0101969Y0083976
X0094882Y0082008
X0094882Y0072165
X0094882Y0064291
X0094882Y0054449
X0101969Y0052480
X0101969Y0060354
X0101969Y0068228
M00
X0010315Y0020079
X0020315Y0020079
X0033937Y0020079
X0043937Y0020079
M00
X0077480Y0026299
X0067480Y0026299
X0057480Y0026299
M00
X0342033Y0234525
X0352033Y0234525
X0347033Y0247709
X0349937Y0104912
X0339937Y0104912
X0344937Y0091728
M00
X0350500Y0622350
X0340500Y0622350
X0370000Y0622350
X0350500Y0597350
X0340500Y0597350
X0370000Y0597350
X0340500Y0445150
X0350500Y0445150
X0340500Y0420150
X0350500Y0420150
X0370000Y0341336
X0370000Y0316336
X0380000Y0341336
X0380000Y0316336
X0380000Y0597350
X0380000Y0622350
M00
X0064174Y0294685
X0107874Y0294685
M00
X0025984Y0279449
X0136221Y0043425
M00
X0060989Y0131906
X0014000Y0255500
X0134016Y0147928
M00
X0024016Y0058661
X0129134Y0247543
M30
